# T6G (Grand Teton) — schematic netlist excerpt (pin names and nets, part order shuffled) for the footprints in the layout excerpt that follows; sources: Cadence DE-HDL packaged netlist, KiCad conversion of 04192023_DAF0TMB3IC0_F0TG_MB_C_brd_V02_OCP.brd

R1498  Q_RES  33 5% CHIP  pkg 0402LF  page 151 : A = SMB_VR_3V3AUX_SDA ; B = SMB_SCM_2_R3_SDA
R5006  Q_RES  1K 1% EMPTY  pkg 0402LF  page 159 : A = PVDD11_S3_P0 ; B = I3C_SPD_DDRAF_CPU0_LVC1_SCL
R1388  Q_RES  1K 1% EMPTY  pkg 0201LF  page 320 : A = P1V8_CPU1_RT_1D ; B = RXDET_BYP_RT_CPU1_P0

(kicad_pcb
	(version 20260206)
	(generator "pcbnew")
	(generator_version "10.0")
	(general
		(thickness 1.6)
		(legacy_teardrops no)
	)
	(paper "A4")
	(title_block
		(title "04192023_DAF0TMB3IC0_F0TG_MB_C_brd_V02_OCP.brd")
		(comment 1 "Grand Teton / footprints 2450-2452 of 8354")
	)
	(layers
		(0 "F.Cu" signal "TOP")
		(4 "In1.Cu" signal "GND")
		(6 "In2.Cu" signal "IN1")
		(8 "In3.Cu" signal "GND1")
		(10 "In4.Cu" signal "IN2")
		(12 "In5.Cu" signal "GND2")
		(14 "In6.Cu" signal "IN3")
		(16 "In7.Cu" signal "GND3")
		(18 "In8.Cu" signal "VCC")
		(20 "In9.Cu" signal "VCC1")
		(22 "In10.Cu" signal "GND4")
		(24 "In11.Cu" signal "IN4")
		(26 "In12.Cu" signal "GND5")
		(28 "In13.Cu" signal "IN5")
		(30 "In14.Cu" signal "GND6")
		(32 "In15.Cu" signal "IN6")
		(34 "In16.Cu" signal "GND7")
		(2 "B.Cu" signal "BOTTOM")
		(9 "F.Adhes" user "F.Adhesive")
		(11 "B.Adhes" user "B.Adhesive")
		(13 "F.Paste" user "Package Geometry/Pastemask Top")
		(15 "B.Paste" user "Package Geometry/Pastemask Bottom")
		(5 "F.SilkS" user "Ref Des/Silkscreen Top")
		(7 "B.SilkS" user "Ref Des/Silkscreen Bottom")
		(1 "F.Mask" user "Board Geometry/Soldermask Top")
		(3 "B.Mask" user "Board Geometry/Soldermask Bottom")
		(17 "Dwgs.User" user "User.Drawings")
		(19 "Cmts.User" user "User.Comments")
		(21 "Eco1.User" user "User.Eco1")
		(23 "Eco2.User" user "User.Eco2")
		(25 "Edge.Cuts" user "Board Geometry/Outline")
		(27 "Margin" user)
		(31 "F.CrtYd" user "Package Geometry/Place Bound Top")
		(29 "B.CrtYd" user "Package Geometry/Place Bound Bottom")
		(35 "F.Fab" user "Ref Des/Assembly Top")
		(33 "B.Fab" user "Ref Des/Assembly Bottom")
	)
	(footprint ""
		(layer "F.Cu")
		(at 74.969878 -389.344154 180)
		(property "Reference" "R1388"
			(at 0 0 180)
			(layer "F.SilkS")
			(hide yes)
			(effects
				(font
					(size 1.27 1.27)
				)
			)
		)
		(property "Value" ""
			(at 0 0 180)
			(layer "F.Fab")
			(effects
				(font
					(size 1.27 1.27)
				)
			)
		)
		(duplicate_pad_numbers_are_jumpers no)
		(fp_line
			(start 0.32512 0.175006)
			(end -0.32512 0.175006)
			(stroke
				(width 0.1)
				(type default)
			)
			(layer "F.Fab")
		)
		(fp_line
			(start 0.32512 -0.175006)
			(end 0.32512 0.175006)
			(stroke
				(width 0.1)
				(type default)
			)
			(layer "F.Fab")
		)
		(fp_line
			(start -0.32512 0.175006)
			(end -0.32512 -0.175006)
			(stroke
				(width 0.1)
				(type default)
			)
			(layer "F.Fab")
		)
		(fp_line
			(start -0.32512 -0.175006)
			(end 0.32512 -0.175006)
			(stroke
				(width 0.1)
				(type default)
			)
			(layer "F.Fab")
		)
		(pad "1" smd rect
			(at -0.2667 0 180)
			(size 0.3048 0.381)
			(layers "F.Cu" "F.Mask" "F.Paste")
			(net "P1V8_CPU1_RT_1D")
		)
		(pad "2" smd rect
			(at 0.2667 0)
			(size 0.3048 0.381)
			(layers "F.Cu" "F.Mask" "F.Paste")
			(net "RXDET_BYP_RT_CPU1_P0")
		)
	)
	(footprint ""
		(layer "F.Cu")
		(at 252.573536 -121.71045 180)
		(property "Reference" "R1498"
			(at 0 0 180)
			(layer "F.SilkS")
			(hide yes)
			(effects
				(font
					(size 1.27 1.27)
				)
			)
		)
		(property "Value" ""
			(at 0 0 180)
			(layer "F.Fab")
			(effects
				(font
					(size 1.27 1.27)
				)
			)
		)
		(duplicate_pad_numbers_are_jumpers no)
		(fp_line
			(start 0.7874 0.4064)
			(end -0.7874 0.4064)
			(stroke
				(width 0.1524)
				(type default)
			)
			(layer "F.SilkS")
		)
		(fp_line
			(start 0.7874 -0.4064)
			(end 0.7874 0.4064)
			(stroke
				(width 0.1524)
				(type default)
			)
			(layer "F.SilkS")
		)
		(fp_line
			(start -0.7874 0.4064)
			(end -0.7874 -0.4064)
			(stroke
				(width 0.1524)
				(type default)
			)
			(layer "F.SilkS")
		)
		(fp_line
			(start -0.7874 -0.4064)
			(end 0.7874 -0.4064)
			(stroke
				(width 0.1524)
				(type default)
			)
			(layer "F.SilkS")
		)
		(fp_line
			(start 0.67945 0.3048)
			(end 0.120396 0.3048)
			(stroke
				(width 0.1)
				(type default)
			)
			(layer "F.Fab")
		)
		(fp_line
			(start 0.67945 -0.3048)
			(end 0.67945 0.3048)
			(stroke
				(width 0.1)
				(type default)
			)
			(layer "F.Fab")
		)
		(fp_line
			(start 0.12065 -0.2794)
			(end 0.12065 -0.3048)
			(stroke
				(width 0.1)
				(type default)
			)
			(layer "F.Fab")
		)
		(fp_line
			(start 0.12065 -0.3048)
			(end 0.67945 -0.3048)
			(stroke
				(width 0.1)
				(type default)
			)
			(layer "F.Fab")
		)
		(fp_line
			(start 0.120396 0.3048)
			(end 0.120396 0.2794)
			(stroke
				(width 0.1)
				(type default)
			)
			(layer "F.Fab")
		)
		(fp_line
			(start 0.120396 0.2794)
			(end -0.12065 0.2794)
			(stroke
				(width 0.1)
				(type default)
			)
			(layer "F.Fab")
		)
		(fp_line
			(start -0.12065 0.3048)
			(end -0.67945 0.3048)
			(stroke
				(width 0.1)
				(type default)
			)
			(layer "F.Fab")
		)
		(fp_line
			(start -0.12065 0.2794)
			(end -0.12065 0.3048)
			(stroke
				(width 0.1)
				(type default)
			)
			(layer "F.Fab")
		)
		(fp_line
			(start -0.12065 -0.2794)
			(end 0.12065 -0.2794)
			(stroke
				(width 0.1)
				(type default)
			)
			(layer "F.Fab")
		)
		(fp_line
			(start -0.12065 -0.305054)
			(end -0.12065 -0.2794)
			(stroke
				(width 0.1)
				(type default)
			)
			(layer "F.Fab")
		)
		(fp_line
			(start -0.67945 0.3048)
			(end -0.67945 -0.305054)
			(stroke
				(width 0.1)
				(type default)
			)
			(layer "F.Fab")
		)
		(fp_line
			(start -0.67945 -0.305054)
			(end -0.12065 -0.305054)
			(stroke
				(width 0.1)
				(type default)
			)
			(layer "F.Fab")
		)
		(pad "1" smd circle
			(at -0.40005 0 180)
			(size 0 0)
			(layers "F.Cu" "F.Mask" "F.Paste")
			(net "SMB_VR_3V3AUX_SDA")
		)
		(pad "2" smd circle
			(at 0.40005 0 180)
			(size 0 0)
			(layers "F.Cu" "F.Mask" "F.Paste")
			(net "SMB_SCM_2_R3_SDA")
		)
	)
	(footprint ""
		(layer "F.Cu")
		(at 297.315128 -147.472908)
		(property "Reference" "R5006"
			(at 0 0 0)
			(layer "F.SilkS")
			(hide yes)
			(effects
				(font
					(size 1.27 1.27)
				)
			)
		)
		(property "Value" ""
			(at 0 0 0)
			(layer "F.Fab")
			(effects
				(font
					(size 1.27 1.27)
				)
			)
		)
		(duplicate_pad_numbers_are_jumpers no)
		(fp_line
			(start -0.7874 -0.4064)
			(end 0.7874 -0.4064)
			(stroke
				(width 0.1524)
				(type default)
			)
			(layer "F.SilkS")
		)
		(fp_line
			(start -0.7874 0.4064)
			(end -0.7874 -0.4064)
			(stroke
				(width 0.1524)
				(type default)
			)
			(layer "F.SilkS")
		)
		(fp_line
			(start 0.7874 -0.4064)
			(end 0.7874 0.4064)
			(stroke
				(width 0.1524)
				(type default)
			)
			(layer "F.SilkS")
		)
		(fp_line
			(start 0.7874 0.4064)
			(end -0.7874 0.4064)
			(stroke
				(width 0.1524)
				(type default)
			)
			(layer "F.SilkS")
		)
		(fp_line
			(start -0.67945 -0.305054)
			(end -0.12065 -0.305054)
			(stroke
				(width 0.1)
				(type default)
			)
			(layer "F.Fab")
		)
		(fp_line
			(start -0.67945 0.3048)
			(end -0.67945 -0.305054)
			(stroke
				(width 0.1)
				(type default)
			)
			(layer "F.Fab")
		)
		(fp_line
			(start -0.12065 -0.305054)
			(end -0.12065 -0.2794)
			(stroke
				(width 0.1)
				(type default)
			)
			(layer "F.Fab")
		)
		(fp_line
			(start -0.12065 -0.2794)
			(end 0.12065 -0.2794)
			(stroke
				(width 0.1)
				(type default)
			)
			(layer "F.Fab")
		)
		(fp_line
			(start -0.12065 0.2794)
			(end -0.12065 0.3048)
			(stroke
				(width 0.1)
				(type default)
			)
			(layer "F.Fab")
		)
		(fp_line
			(start -0.12065 0.3048)
			(end -0.67945 0.3048)
			(stroke
				(width 0.1)
				(type default)
			)
			(layer "F.Fab")
		)
		(fp_line
			(start 0.120396 0.2794)
			(end -0.12065 0.2794)
			(stroke
				(width 0.1)
				(type default)
			)
			(layer "F.Fab")
		)
		(fp_line
			(start 0.120396 0.3048)
			(end 0.120396 0.2794)
			(stroke
				(width 0.1)
				(type default)
			)
			(layer "F.Fab")
		)
		(fp_line
			(start 0.12065 -0.3048)
			(end 0.67945 -0.3048)
			(stroke
				(width 0.1)
				(type default)
			)
			(layer "F.Fab")
		)
		(fp_line
			(start 0.12065 -0.2794)
			(end 0.12065 -0.3048)
			(stroke
				(width 0.1)
				(type default)
			)
			(layer "F.Fab")
		)
		(fp_line
			(start 0.67945 -0.3048)
			(end 0.67945 0.3048)
			(stroke
				(width 0.1)
				(type default)
			)
			(layer "F.Fab")
		)
		(fp_line
			(start 0.67945 0.3048)
			(end 0.120396 0.3048)
			(stroke
				(width 0.1)
				(type default)
			)
			(layer "F.Fab")
		)
		(pad "1" smd circle
			(at -0.40005 0)
			(size 0 0)
			(layers "F.Cu" "F.Mask" "F.Paste")
			(net "PVDD11_S3_P0")
		)
		(pad "2" smd circle
			(at 0.40005 0)
			(size 0 0)
			(layers "F.Cu" "F.Mask" "F.Paste")
			(net "I3C_SPD_DDRAF_CPU0_LVC1_SCL")
		)
	)
)
